(kicad_pcb
	(version 20221018)
	(generator pcbnew)
	(general
    (thickness 1.7403)
  )
	(paper "A4")
	(title_block
    (title "Data Center RDIMM DDR4 Tester")
    (date "2024-09-30")
    (rev "1.2.4")
		(comment 9 "footprint 168 of 690 (U15), pads 620-676 of 676")
	)
	(layers
    (0 "F.Cu" signal)
    (1 "In1.Cu" power)
    (2 "In2.Cu" signal)
    (3 "In3.Cu" power)
    (4 "In4.Cu" power)
    (5 "In5.Cu" signal)
    (6 "In6.Cu" power)
    (7 "In7.Cu" signal)
    (8 "In8.Cu" power)
    (9 "In9.Cu" signal)
    (10 "In10.Cu" power)
    (31 "B.Cu" signal)
    (32 "B.Adhes" user "B.Adhesive")
    (33 "F.Adhes" user "F.Adhesive")
    (34 "B.Paste" user)
    (35 "F.Paste" user)
    (36 "B.SilkS" user "B.Silkscreen")
    (37 "F.SilkS" user "F.Silkscreen")
    (38 "B.Mask" user)
    (39 "F.Mask" user)
    (40 "Dwgs.User" user "User.Drawings")
    (41 "Cmts.User" user "User.Comments")
    (42 "Eco1.User" user "User.Eco1")
    (43 "Eco2.User" user "User.Eco2")
    (44 "Edge.Cuts" user)
    (45 "Margin" user)
    (46 "B.CrtYd" user "B.Courtyard")
    (47 "F.CrtYd" user "F.Courtyard")
    (48 "B.Fab" user)
    (49 "F.Fab" user)
  )
	(footprint "data-center-rdimm-ddr4-tester-footprints:BGA-676_27x27mm_Layout26x26_P1X1mm"
    (layer "F.Cu")
    (at 183.635 90.06 180)
    (descr "FPGA XC7K160TFBG676")
    (tags "FPGA XC7K160TFBG676")
    (property "Author" "Antmicro")
    (property "License" "Apache-2.0")
    (property "MPN" "XC7K160T-FFG676")
    (property "Manufacturer" "AMD-Xilinx")
    (property "Sheetfile" "config-spi.kicad_sch")
    (property "Sheetname" "Config SPI flash")
    (property "ki_description" "Kintex®-7 Field Programmable Gate Array (FPGA) IC 300 4976640 65600 676-BBGA, FCBGA")
    (property "ki_keywords" "SMT, MICROCONTROLLER, IC, FPGA")
    (attr smd)
    (fp_text reference "U15" (at -10.675 -14.7 180) (layer "F.SilkS")
        (effects (font (size 0.7 0.7) (thickness 0.15)) (justify left bottom))
    )
    (fp_text value "XC7K160T-FFG676" (at 0 15.5 180) (layer "F.Fab")
        (effects (font (size 0.7 0.7) (thickness 0.15)) (justify left bottom))
    )
    (pad "V22" smd circle (at 8.499 4.499 180) (size 0.5 0.5) (layers "F.Cu" "F.Paste" "F.Mask")
      (net 902 "unconnected-(U15A-IO_L1N_T0_12-PadV22)") (pinfunction "IO_L1N_T0_12") (pintype "bidirectional+no_connect") (die_length 10.787))
    (pad "V23" smd circle (at 9.499 4.499 180) (size 0.5 0.5) (layers "F.Cu" "F.Paste" "F.Mask")
      (net 905 "unconnected-(U15A-IO_L3P_T0_DQS_12-PadV23)") (pinfunction "IO_L3P_T0_DQS_12") (pintype "bidirectional+no_connect") (die_length 12.224))
    (pad "V24" smd circle (at 10.499 4.499 180) (size 0.5 0.5) (layers "F.Cu" "F.Paste" "F.Mask")
      (net 906 "unconnected-(U15A-IO_L3N_T0_DQS_12-PadV24)") (pinfunction "IO_L3N_T0_DQS_12") (pintype "bidirectional+no_connect") (die_length 12.691))
    (pad "V25" smd circle (at 11.499 4.499 180) (size 0.5 0.5) (layers "F.Cu" "F.Paste" "F.Mask")
      (net 9 "GND") (pinfunction "GND") (pintype "passive"))
    (pad "V26" smd circle (at 12.499 4.499 180) (size 0.5 0.5) (layers "F.Cu" "F.Paste" "F.Mask")
      (net 41 "ETH_RXD2") (pinfunction "IO_L4N_T0_12") (pintype "bidirectional") (die_length 15.219))
    (pad "W1" smd circle (at -12.5 5.499 180) (size 0.5 0.5) (layers "F.Cu" "F.Paste" "F.Mask")
      (net 323 "DQS11_P") (pinfunction "IO_L10P_T1_34") (pintype "bidirectional") (die_length 18.423))
    (pad "W2" smd circle (at -11.5 5.499 180) (size 0.5 0.5) (layers "F.Cu" "F.Paste" "F.Mask")
      (net 9 "GND") (pinfunction "GND") (pintype "passive"))
    (pad "W3" smd circle (at -10.5 5.499 180) (size 0.5 0.5) (layers "F.Cu" "F.Paste" "F.Mask")
      (net 321 "DQS10_N") (pinfunction "IO_L4N_T0_34") (pintype "bidirectional") (die_length 18.698))
    (pad "W4" smd circle (at -9.5 5.499 180) (size 0.5 0.5) (layers "F.Cu" "F.Paste" "F.Mask")
      (net 245 "DQ12") (pinfunction "IO_L6N_T0_VREF_34") (pintype "bidirectional") (die_length 18.8))
    (pad "W5" smd circle (at -8.5 5.499 180) (size 0.5 0.5) (layers "F.Cu" "F.Paste" "F.Mask")
      (net 317 "DQS9_N") (pinfunction "IO_L3N_T0_DQS_34") (pintype "bidirectional") (die_length 17.539))
    (pad "W6" smd circle (at -7.5 5.499 180) (size 0.5 0.5) (layers "F.Cu" "F.Paste" "F.Mask")
      (net 316 "DQS9_P") (pinfunction "IO_L3P_T0_DQS_34") (pintype "bidirectional") (die_length 17.741))
    (pad "W7" smd circle (at -6.5 5.499 180) (size 0.5 0.5) (layers "F.Cu" "F.Paste" "F.Mask")
      (net 77 "VDDQ") (pinfunction "VCCO_33") (pintype "passive"))
    (pad "W8" smd circle (at -5.5 5.499 180) (size 0.5 0.5) (layers "F.Cu" "F.Paste" "F.Mask")
      (net 909 "unconnected-(U15G-IO_L6N_T0_VREF_33-PadW8)") (pinfunction "IO_L6N_T0_VREF_33") (pintype "bidirectional+no_connect") (die_length 12.359))
    (pad "W9" smd circle (at -4.5 5.499 180) (size 0.5 0.5) (layers "F.Cu" "F.Paste" "F.Mask")
      (net 231 "ODT1\\NC") (pinfunction "IO_L3N_T0_DQS_33") (pintype "bidirectional") (die_length 12.347))
    (pad "W10" smd circle (at -3.5 5.499 180) (size 0.5 0.5) (layers "F.Cu" "F.Paste" "F.Mask")
      (net 201 "NC\\C2") (pinfunction "IO_L3P_T0_DQS_33") (pintype "bidirectional") (die_length 12.577))
    (pad "W11" smd circle (at -2.5 5.499 180) (size 0.5 0.5) (layers "F.Cu" "F.Paste" "F.Mask")
      (net 198 "~{CS3}\\C1,NC") (pinfunction "IO_L1N_T0_33") (pintype "bidirectional") (die_length 9.991))
    (pad "W12" smd circle (at -1.5 5.499 180) (size 0.5 0.5) (layers "F.Cu" "F.Paste" "F.Mask")
      (net 9 "GND") (pinfunction "GND") (pintype "passive"))
    (pad "W13" smd circle (at -0.5 5.499 180) (size 0.5 0.5) (layers "F.Cu" "F.Paste" "F.Mask")
      (net 910 "unconnected-(U15F-IO_25_VRP_32-PadW13)") (pinfunction "IO_25_VRP_32") (pintype "bidirectional+no_connect") (die_length 8.841))
    (pad "W14" smd circle (at 0.499 5.499 180) (size 0.5 0.5) (layers "F.Cu" "F.Paste" "F.Mask")
      (net 221 "DQ60") (pinfunction "IO_L24N_T3_32") (pintype "bidirectional") (die_length 12.441))
    (pad "W15" smd circle (at 1.499 5.499 180) (size 0.5 0.5) (layers "F.Cu" "F.Paste" "F.Mask")
      (net 343 "DQS16_P") (pinfunction "IO_L22P_T3_32") (pintype "bidirectional") (die_length 13.547))
    (pad "W16" smd circle (at 2.499 5.499 180) (size 0.5 0.5) (layers "F.Cu" "F.Paste" "F.Mask")
      (net 345 "DQS16_N") (pinfunction "IO_L22N_T3_32") (pintype "bidirectional") (die_length 15.068))
    (pad "W17" smd circle (at 3.499 5.499 180) (size 0.5 0.5) (layers "F.Cu" "F.Paste" "F.Mask")
      (net 77 "VDDQ") (pinfunction "VCCO_32") (pintype "passive"))
    (pad "W18" smd circle (at 4.499 5.499 180) (size 0.5 0.5) (layers "F.Cu" "F.Paste" "F.Mask")
      (net 217 "DQ62") (pinfunction "IO_L21P_T3_DQS_32") (pintype "bidirectional") (die_length 16.431))
    (pad "W19" smd circle (at 5.499 5.499 180) (size 0.5 0.5) (layers "F.Cu" "F.Paste" "F.Mask")
      (net 216 "DQ58") (pinfunction "IO_L21N_T3_DQS_32") (pintype "bidirectional") (die_length 16.437))
    (pad "W20" smd circle (at 6.499 5.499 180) (size 0.5 0.5) (layers "F.Cu" "F.Paste" "F.Mask")
      (net 911 "unconnected-(U15A-IO_L15P_T2_DQS_12-PadW20)") (pinfunction "IO_L15P_T2_DQS_12") (pintype "bidirectional+no_connect") (die_length 9.921))
    (pad "W21" smd circle (at 7.499 5.499 180) (size 0.5 0.5) (layers "F.Cu" "F.Paste" "F.Mask")
      (net 912 "unconnected-(U15A-IO_L6N_T0_VREF_12-PadW21)") (pinfunction "IO_L6N_T0_VREF_12") (pintype "bidirectional+no_connect") (die_length 9.947))
    (pad "W22" smd circle (at 8.499 5.499 180) (size 0.5 0.5) (layers "F.Cu" "F.Paste" "F.Mask")
      (net 9 "GND") (pinfunction "GND") (pintype "passive"))
    (pad "W23" smd circle (at 9.499 5.499 180) (size 0.5 0.5) (layers "F.Cu" "F.Paste" "F.Mask")
      (net 913 "unconnected-(U15A-IO_L8P_T1_12-PadW23)") (pinfunction "IO_L8P_T1_12") (pintype "bidirectional+no_connect") (die_length 12.009))
    (pad "W24" smd circle (at 10.499 5.499 180) (size 0.5 0.5) (layers "F.Cu" "F.Paste" "F.Mask")
      (net 36 "ETH_TXD0") (pinfunction "IO_L8N_T1_12") (pintype "bidirectional") (die_length 13.111))
    (pad "W25" smd circle (at 11.499 5.499 180) (size 0.5 0.5) (layers "F.Cu" "F.Paste" "F.Mask")
      (net 27 "ETH_RXD1") (pinfunction "IO_L5P_T0_12") (pintype "bidirectional") (die_length 14.107))
    (pad "W26" smd circle (at 12.499 5.499 180) (size 0.5 0.5) (layers "F.Cu" "F.Paste" "F.Mask")
      (net 26 "ETH_RXD0") (pinfunction "IO_L5N_T0_12") (pintype "bidirectional") (die_length 15.45))
    (pad "Y1" smd circle (at -12.5 6.499 180) (size 0.5 0.5) (layers "F.Cu" "F.Paste" "F.Mask")
      (net 325 "DQS11_N") (pinfunction "IO_L10N_T1_34") (pintype "bidirectional") (die_length 20.111))
    (pad "Y2" smd circle (at -11.5 6.499 180) (size 0.5 0.5) (layers "F.Cu" "F.Paste" "F.Mask")
      (net 281 "DQ17") (pinfunction "IO_L7N_T1_34") (pintype "bidirectional") (die_length 18.743))
    (pad "Y3" smd circle (at -10.5 6.499 180) (size 0.5 0.5) (layers "F.Cu" "F.Paste" "F.Mask")
      (net 293 "DQ9") (pinfunction "IO_L7P_T1_34") (pintype "bidirectional") (die_length 18.285))
    (pad "Y4" smd circle (at -9.5 6.499 180) (size 0.5 0.5) (layers "F.Cu" "F.Paste" "F.Mask")
      (net 77 "VDDQ") (pinfunction "VCCO_34") (pintype "passive"))
    (pad "Y5" smd circle (at -8.5 6.499 180) (size 0.5 0.5) (layers "F.Cu" "F.Paste" "F.Mask")
      (net 315 "DQS0_N") (pinfunction "IO_L17N_T2_34") (pintype "bidirectional") (die_length 15.693))
    (pad "Y6" smd circle (at -7.5 6.499 180) (size 0.5 0.5) (layers "F.Cu" "F.Paste" "F.Mask")
      (net 314 "DQS0_P") (pinfunction "IO_L17P_T2_34") (pintype "bidirectional") (die_length 17.912))
    (pad "Y7" smd circle (at -6.5 6.499 180) (size 0.5 0.5) (layers "F.Cu" "F.Paste" "F.Mask")
      (net 658 "Net-(U15G-IO_L4N_T0_33)") (pinfunction "IO_L4N_T0_33") (pintype "bidirectional") (die_length 13.835))
    (pad "Y8" smd circle (at -5.5 6.499 180) (size 0.5 0.5) (layers "F.Cu" "F.Paste" "F.Mask")
      (net 264 "~{ACT}") (pinfunction "IO_L4P_T0_33") (pintype "bidirectional") (die_length 13.201))
    (pad "Y9" smd circle (at -4.5 6.499 180) (size 0.5 0.5) (layers "F.Cu" "F.Paste" "F.Mask")
      (net 9 "GND") (pinfunction "GND") (pintype "passive"))
    (pad "Y10" smd circle (at -3.5 6.499 180) (size 0.5 0.5) (layers "F.Cu" "F.Paste" "F.Mask")
      (net 209 "~{SAVE}") (pinfunction "IO_L5N_T0_33") (pintype "bidirectional") (die_length 14.206))
    (pad "Y11" smd circle (at -2.5 6.499 180) (size 0.5 0.5) (layers "F.Cu" "F.Paste" "F.Mask")
      (net 234 "~{CS1}\\NC") (pinfunction "IO_L5P_T0_33") (pintype "bidirectional") (die_length 15.036))
    (pad "Y12" smd circle (at -1.5 6.499 180) (size 0.5 0.5) (layers "F.Cu" "F.Paste" "F.Mask")
      (net 208 "A10\\AP") (pinfunction "IO_L18N_T2_33") (pintype "bidirectional") (die_length 14.615))
    (pad "Y13" smd circle (at -0.5 6.499 180) (size 0.5 0.5) (layers "F.Cu" "F.Paste" "F.Mask")
      (net 235 "ODT0") (pinfunction "IO_L18P_T2_33") (pintype "bidirectional") (die_length 15.191))
    (pad "Y14" smd circle (at 0.499 6.499 180) (size 0.5 0.5) (layers "F.Cu" "F.Paste" "F.Mask")
      (net 77 "VDDQ") (pinfunction "VCCO_32") (pintype "passive"))
    (pad "Y15" smd circle (at 1.499 6.499 180) (size 0.5 0.5) (layers "F.Cu" "F.Paste" "F.Mask")
      (net 191 "DQ61") (pinfunction "IO_L9P_T1_DQS_32") (pintype "bidirectional") (die_length 13.423))
    (pad "Y16" smd circle (at 2.499 6.499 180) (size 0.5 0.5) (layers "F.Cu" "F.Paste" "F.Mask")
      (net 192 "DQ57") (pinfunction "IO_L9N_T1_DQS_32") (pintype "bidirectional") (die_length 13.009))
    (pad "Y17" smd circle (at 3.499 6.499 180) (size 0.5 0.5) (layers "F.Cu" "F.Paste" "F.Mask")
      (net 338 "DQS6_P") (pinfunction "IO_L19P_T3_32") (pintype "bidirectional") (die_length 15.853))
    (pad "Y18" smd circle (at 4.499 6.499 180) (size 0.5 0.5) (layers "F.Cu" "F.Paste" "F.Mask")
      (net 340 "DQS6_N") (pinfunction "IO_L19N_T3_VREF_32") (pintype "bidirectional") (die_length 15))
    (pad "Y19" smd circle (at 5.499 6.499 180) (size 0.5 0.5) (layers "F.Cu" "F.Paste" "F.Mask")
      (net 9 "GND") (pinfunction "GND") (pintype "passive"))
    (pad "Y20" smd circle (at 6.499 6.499 180) (size 0.5 0.5) (layers "F.Cu" "F.Paste" "F.Mask")
      (net 183 "ETH_INT_N") (pinfunction "IO_25_12") (pintype "bidirectional") (die_length 8.585))
    (pad "Y21" smd circle (at 7.499 6.499 180) (size 0.5 0.5) (layers "F.Cu" "F.Paste" "F.Mask")
      (net 33 "ETH_TXD3") (pinfunction "IO_L15N_T2_DQS_12") (pintype "bidirectional") (die_length 9.864))
    (pad "Y22" smd circle (at 8.499 6.499 180) (size 0.5 0.5) (layers "F.Cu" "F.Paste" "F.Mask")
      (net 32 "ETH_TXD2") (pinfunction "IO_L13P_T2_MRCC_12") (pintype "bidirectional") (die_length 11.571))
    (pad "Y23" smd circle (at 9.499 6.499 180) (size 0.5 0.5) (layers "F.Cu" "F.Paste" "F.Mask")
      (net 40 "ETH_RX_CLK") (pinfunction "IO_L12P_T1_MRCC_12") (pintype "bidirectional") (die_length 12.692))
    (pad "Y24" smd circle (at 10.499 6.499 180) (size 0.5 0.5) (layers "F.Cu" "F.Paste" "F.Mask")
      (net 143 "3V3_SYS") (pinfunction "VCCO_12") (pintype "passive"))
    (pad "Y25" smd circle (at 11.499 6.499 180) (size 0.5 0.5) (layers "F.Cu" "F.Paste" "F.Mask")
      (net 38 "ETH_RX_DV") (pinfunction "IO_L10P_T1_12") (pintype "bidirectional") (die_length 14.135))
    (pad "Y26" smd circle (at 12.499 6.499 180) (size 0.5 0.5) (layers "F.Cu" "F.Paste" "F.Mask")
      (net 31 "ETH_TXD1") (pinfunction "IO_L10N_T1_12") (pintype "bidirectional") (die_length 15.98))
  )
)
